# S9S_MB_2U (Grand Teton) — schematic netlist excerpt (pin names and nets, part order shuffled) for the footprints in the layout excerpt that follows; sources: Cadence DE-HDL packaged netlist, KiCad conversion of 03242023_DA0F0TMBIJ0_F0T_Motherboard_J_brd_V01_OCP.brd

R3047  Q_RES  0 5% CHIP  pkg 0402LF  page 214 : A = MB0_P12V_STBY_PWRGD ; B = PWRGD_PS_PWROK_PLD
C895  Q_CAP_DIFFBUS  DIFF BUS_0.22UF 6.3V 20% X6S  pkg C0201  page 174 : \1\ = P5E_CPU0_PE3_TX_C_DP<3> ; \2\ = P5E_CPU0_PE3_TX_DP<3>
PC1657  Q_CAP  100NF 50V 10% X7R  pkg C0402  page 289 : A = P12V_AUX ; B = GND

(kicad_pcb
	(version 20260206)
	(generator "pcbnew")
	(generator_version "10.0")
	(general
		(thickness 1.6)
		(legacy_teardrops no)
	)
	(paper "A4")
	(title_block
		(title "03242023_DA0F0TMBIJ0_F0T_Motherboard_J_brd_V01_OCP.brd")
		(comment 1 "Grand Teton / footprints 2430-2432 of 6105")
	)
	(layers
		(0 "F.Cu" signal "TOP")
		(4 "In1.Cu" signal "GND")
		(6 "In2.Cu" signal "IN1")
		(8 "In3.Cu" signal "GND1")
		(10 "In4.Cu" signal "IN2")
		(12 "In5.Cu" signal "GND2")
		(14 "In6.Cu" signal "IN3")
		(16 "In7.Cu" signal "GND3")
		(18 "In8.Cu" signal "VCC")
		(20 "In9.Cu" signal "VCC1")
		(22 "In10.Cu" signal "GND4")
		(24 "In11.Cu" signal "IN4")
		(26 "In12.Cu" signal "GND5")
		(28 "In13.Cu" signal "IN5")
		(30 "In14.Cu" signal "GND6")
		(32 "In15.Cu" signal "IN6")
		(34 "In16.Cu" signal "GND7")
		(2 "B.Cu" signal "BOTTOM")
		(9 "F.Adhes" user "F.Adhesive")
		(11 "B.Adhes" user "B.Adhesive")
		(13 "F.Paste" user "Package Geometry/Pastemask Top")
		(15 "B.Paste" user "Package Geometry/Pastemask Bottom")
		(5 "F.SilkS" user "Ref Des/Silkscreen Top")
		(7 "B.SilkS" user "Ref Des/Silkscreen Bottom")
		(1 "F.Mask" user "Board Geometry/Soldermask Top")
		(3 "B.Mask" user "Board Geometry/Soldermask Bottom")
		(17 "Dwgs.User" user "User.Drawings")
		(19 "Cmts.User" user "User.Comments")
		(21 "Eco1.User" user "User.Eco1")
		(23 "Eco2.User" user "User.Eco2")
		(25 "Edge.Cuts" user "Board Geometry/Outline")
		(27 "Margin" user)
		(31 "F.CrtYd" user "Package Geometry/Place Bound Top")
		(29 "B.CrtYd" user "Package Geometry/Place Bound Bottom")
		(35 "F.Fab" user "Ref Des/Assembly Top")
		(33 "B.Fab" user "Ref Des/Assembly Bottom")
	)
	(footprint ""
		(layer "F.Cu")
		(at 410.41701 -408.517344 -90)
		(property "Reference" "C895"
			(at 0 0 270)
			(layer "F.SilkS")
			(hide yes)
			(effects
				(font
					(size 1.27 1.27)
				)
			)
		)
		(property "Value" ""
			(at 0 0 270)
			(layer "F.Fab")
			(effects
				(font
					(size 1.27 1.27)
				)
			)
		)
		(duplicate_pad_numbers_are_jumpers no)
		(fp_line
			(start -0.299974 0.150114)
			(end -0.299974 -0.150114)
			(stroke
				(width 0.1)
				(type default)
			)
			(layer "F.Fab")
		)
		(fp_line
			(start 0.299974 0.150114)
			(end -0.299974 0.150114)
			(stroke
				(width 0.1)
				(type default)
			)
			(layer "F.Fab")
		)
		(fp_line
			(start -0.299974 -0.150114)
			(end 0.299974 -0.150114)
			(stroke
				(width 0.1)
				(type default)
			)
			(layer "F.Fab")
		)
		(fp_line
			(start 0.299974 -0.150114)
			(end 0.299974 0.150114)
			(stroke
				(width 0.1)
				(type default)
			)
			(layer "F.Fab")
		)
		(pad "1" smd rect
			(at -0.2667 0 270)
			(size 0.3048 0.381)
			(layers "F.Cu" "F.Mask" "F.Paste")
			(net "P5E_CPU0_PE3_TX_C_DP<3>")
		)
		(pad "2" smd rect
			(at 0.2667 0 270)
			(size 0.3048 0.381)
			(layers "F.Cu" "F.Mask" "F.Paste")
			(net "P5E_CPU0_PE3_TX_DP<3>")
		)
	)
	(footprint ""
		(layer "F.Cu")
		(at 42.446194 -366.62106)
		(property "Reference" "PC1657"
			(at 0 0 0)
			(layer "F.SilkS")
			(hide yes)
			(effects
				(font
					(size 1.27 1.27)
				)
			)
		)
		(property "Value" ""
			(at 0 0 0)
			(layer "F.Fab")
			(effects
				(font
					(size 1.27 1.27)
				)
			)
		)
		(duplicate_pad_numbers_are_jumpers no)
		(fp_line
			(start -0.7874 -0.4064)
			(end 0.7874 -0.4064)
			(stroke
				(width 0.1524)
				(type default)
			)
			(layer "F.SilkS")
		)
		(fp_line
			(start -0.7874 0.4064)
			(end -0.7874 -0.4064)
			(stroke
				(width 0.1524)
				(type default)
			)
			(layer "F.SilkS")
		)
		(fp_line
			(start 0.7874 -0.4064)
			(end 0.7874 0.4064)
			(stroke
				(width 0.1524)
				(type default)
			)
			(layer "F.SilkS")
		)
		(fp_line
			(start 0.7874 0.4064)
			(end -0.7874 0.4064)
			(stroke
				(width 0.1524)
				(type default)
			)
			(layer "F.SilkS")
		)
		(fp_line
			(start -0.67945 -0.305054)
			(end -0.12065 -0.305054)
			(stroke
				(width 0.1)
				(type default)
			)
			(layer "F.Fab")
		)
		(fp_line
			(start -0.67945 0.3048)
			(end -0.67945 -0.305054)
			(stroke
				(width 0.1)
				(type default)
			)
			(layer "F.Fab")
		)
		(fp_line
			(start -0.12065 -0.305054)
			(end -0.12065 -0.2794)
			(stroke
				(width 0.1)
				(type default)
			)
			(layer "F.Fab")
		)
		(fp_line
			(start -0.12065 -0.2794)
			(end 0.12065 -0.2794)
			(stroke
				(width 0.1)
				(type default)
			)
			(layer "F.Fab")
		)
		(fp_line
			(start -0.12065 0.2794)
			(end -0.12065 0.3048)
			(stroke
				(width 0.1)
				(type default)
			)
			(layer "F.Fab")
		)
		(fp_line
			(start -0.12065 0.3048)
			(end -0.67945 0.3048)
			(stroke
				(width 0.1)
				(type default)
			)
			(layer "F.Fab")
		)
		(fp_line
			(start 0.120396 0.2794)
			(end -0.12065 0.2794)
			(stroke
				(width 0.1)
				(type default)
			)
			(layer "F.Fab")
		)
		(fp_line
			(start 0.120396 0.3048)
			(end 0.120396 0.2794)
			(stroke
				(width 0.1)
				(type default)
			)
			(layer "F.Fab")
		)
		(fp_line
			(start 0.12065 -0.3048)
			(end 0.67945 -0.3048)
			(stroke
				(width 0.1)
				(type default)
			)
			(layer "F.Fab")
		)
		(fp_line
			(start 0.12065 -0.2794)
			(end 0.12065 -0.3048)
			(stroke
				(width 0.1)
				(type default)
			)
			(layer "F.Fab")
		)
		(fp_line
			(start 0.67945 -0.3048)
			(end 0.67945 0.3048)
			(stroke
				(width 0.1)
				(type default)
			)
			(layer "F.Fab")
		)
		(fp_line
			(start 0.67945 0.3048)
			(end 0.120396 0.3048)
			(stroke
				(width 0.1)
				(type default)
			)
			(layer "F.Fab")
		)
		(pad "1" smd circle
			(at -0.40005 0)
			(size 0 0)
			(layers "F.Cu" "F.Mask" "F.Paste")
			(net "P12V_AUX")
		)
		(pad "2" smd circle
			(at 0.40005 0)
			(size 0 0)
			(layers "F.Cu" "F.Mask" "F.Paste")
			(net "GND")
		)
	)
	(footprint ""
		(layer "F.Cu")
		(at 172.77588 -133.695948 -90)
		(property "Reference" "R3047"
			(at 0 0 270)
			(layer "F.SilkS")
			(hide yes)
			(effects
				(font
					(size 1.27 1.27)
				)
			)
		)
		(property "Value" ""
			(at 0 0 270)
			(layer "F.Fab")
			(effects
				(font
					(size 1.27 1.27)
				)
			)
		)
		(duplicate_pad_numbers_are_jumpers no)
		(fp_line
			(start -0.7874 0.4064)
			(end -0.7874 -0.4064)
			(stroke
				(width 0.1524)
				(type default)
			)
			(layer "F.SilkS")
		)
		(fp_line
			(start 0.7874 0.4064)
			(end -0.7874 0.4064)
			(stroke
				(width 0.1524)
				(type default)
			)
			(layer "F.SilkS")
		)
		(fp_line
			(start -0.7874 -0.4064)
			(end 0.7874 -0.4064)
			(stroke
				(width 0.1524)
				(type default)
			)
			(layer "F.SilkS")
		)
		(fp_line
			(start 0.7874 -0.4064)
			(end 0.7874 0.4064)
			(stroke
				(width 0.1524)
				(type default)
			)
			(layer "F.SilkS")
		)
		(fp_line
			(start -0.67945 0.3048)
			(end -0.67945 -0.305054)
			(stroke
				(width 0.1)
				(type default)
			)
			(layer "F.Fab")
		)
		(fp_line
			(start -0.12065 0.3048)
			(end -0.67945 0.3048)
			(stroke
				(width 0.1)
				(type default)
			)
			(layer "F.Fab")
		)
		(fp_line
			(start 0.120396 0.3048)
			(end 0.120396 0.2794)
			(stroke
				(width 0.1)
				(type default)
			)
			(layer "F.Fab")
		)
		(fp_line
			(start 0.67945 0.3048)
			(end 0.120396 0.3048)
			(stroke
				(width 0.1)
				(type default)
			)
			(layer "F.Fab")
		)
		(fp_line
			(start -0.12065 0.2794)
			(end -0.12065 0.3048)
			(stroke
				(width 0.1)
				(type default)
			)
			(layer "F.Fab")
		)
		(fp_line
			(start 0.120396 0.2794)
			(end -0.12065 0.2794)
			(stroke
				(width 0.1)
				(type default)
			)
			(layer "F.Fab")
		)
		(fp_line
			(start -0.12065 -0.2794)
			(end 0.12065 -0.2794)
			(stroke
				(width 0.1)
				(type default)
			)
			(layer "F.Fab")
		)
		(fp_line
			(start 0.12065 -0.2794)
			(end 0.12065 -0.3048)
			(stroke
				(width 0.1)
				(type default)
			)
			(layer "F.Fab")
		)
		(fp_line
			(start 0.12065 -0.3048)
			(end 0.67945 -0.3048)
			(stroke
				(width 0.1)
				(type default)
			)
			(layer "F.Fab")
		)
		(fp_line
			(start 0.67945 -0.3048)
			(end 0.67945 0.3048)
			(stroke
				(width 0.1)
				(type default)
			)
			(layer "F.Fab")
		)
		(fp_line
			(start -0.67945 -0.305054)
			(end -0.12065 -0.305054)
			(stroke
				(width 0.1)
				(type default)
			)
			(layer "F.Fab")
		)
		(fp_line
			(start -0.12065 -0.305054)
			(end -0.12065 -0.2794)
			(stroke
				(width 0.1)
				(type default)
			)
			(layer "F.Fab")
		)
		(pad "1" smd circle
			(at -0.40005 0 270)
			(size 0 0)
			(layers "F.Cu" "F.Mask" "F.Paste")
			(net "MB0_P12V_STBY_PWRGD")
		)
		(pad "2" smd circle
			(at 0.40005 0 270)
			(size 0 0)
			(layers "F.Cu" "F.Mask" "F.Paste")
			(net "PWRGD_PS_PWROK_PLD")
		)
	)
)
